# T6G (Grand Teton) — schematic netlist excerpt (pin names and nets, part order shuffled) for the footprints in the layout excerpt that follows; sources: Cadence DE-HDL packaged netlist, KiCad conversion of 04192023_DAF0TMB3IC0_F0TG_MB_C_brd_V02_OCP.brd

PU37  ISL99390FRZTR5935  ISL99390FRZ-TR5935 IC  pkg QFN21_6X5XB  page 219
  VOS  = PVDDCR_CPU1_P1_VOS3
  AGND  = GND
  VCC  = PVDDCR_CPU1_P1_VCC3
  PVCC  = PVDDCR_CPU1_P1_PVCC
  PGND1  = GND
  GL1  = NC_PVDDCR_CPU1_P1_GL1_3
  PGND2  = GND
  SW  = SW_PVDDCR_CPU1_P1_SW3
  VIN1  = SW_P12V_AUX_PVDDCR_CPU1_P1_FLT
  VIN2  = SW_P12V_AUX_PVDDCR_CPU1_P1_FLT
  DNC  = NC_PVDDCR_CPU1_P1_DNC3
  PHASE  = SW_PVDDCR_CPU1_P1_BOOTR3
  BOOT  = SW_PVDDCR_CPU1_P1_BOOT3
  PWM  = PVDDCR_CPU1_P1_PWM3
  EN  = PVDDCR_CPU1_P1_VCC3
  TOUT_FLT  = PVDDCR_CPU1_P1_TEMP0
  LSET  = PVDDCR_CPU1_P1_LSET3
  IOUT  = PVDDCR_CPU1_P1_IMON3
  REFIN  = PVDDCR_CPU1_P1_VCCS
  PGND3  = GND
  GL2  = NC_PVDDCR_CPU1_P1_GL2_3

(kicad_pcb
	(version 20260206)
	(generator "pcbnew")
	(generator_version "10.0")
	(general
		(thickness 1.6)
		(legacy_teardrops no)
	)
	(paper "A4")
	(title_block
		(title "04192023_DAF0TMB3IC0_F0TG_MB_C_brd_V02_OCP.brd")
		(comment 1 "Grand Teton / footprints 3671-3671 of 8354")
	)
	(layers
		(0 "F.Cu" signal "TOP")
		(4 "In1.Cu" signal "GND")
		(6 "In2.Cu" signal "IN1")
		(8 "In3.Cu" signal "GND1")
		(10 "In4.Cu" signal "IN2")
		(12 "In5.Cu" signal "GND2")
		(14 "In6.Cu" signal "IN3")
		(16 "In7.Cu" signal "GND3")
		(18 "In8.Cu" signal "VCC")
		(20 "In9.Cu" signal "VCC1")
		(22 "In10.Cu" signal "GND4")
		(24 "In11.Cu" signal "IN4")
		(26 "In12.Cu" signal "GND5")
		(28 "In13.Cu" signal "IN5")
		(30 "In14.Cu" signal "GND6")
		(32 "In15.Cu" signal "IN6")
		(34 "In16.Cu" signal "GND7")
		(2 "B.Cu" signal "BOTTOM")
		(9 "F.Adhes" user "F.Adhesive")
		(11 "B.Adhes" user "B.Adhesive")
		(13 "F.Paste" user "Package Geometry/Pastemask Top")
		(15 "B.Paste" user "Package Geometry/Pastemask Bottom")
		(5 "F.SilkS" user "Ref Des/Silkscreen Top")
		(7 "B.SilkS" user "Ref Des/Silkscreen Bottom")
		(1 "F.Mask" user "Board Geometry/Soldermask Top")
		(3 "B.Mask" user "Board Geometry/Soldermask Bottom")
		(17 "Dwgs.User" user "User.Drawings")
		(19 "Cmts.User" user "User.Comments")
		(21 "Eco1.User" user "User.Eco1")
		(23 "Eco2.User" user "User.Eco2")
		(25 "Edge.Cuts" user "Board Geometry/Outline")
		(27 "Margin" user)
		(31 "F.CrtYd" user "Package Geometry/Place Bound Top")
		(29 "B.CrtYd" user "Package Geometry/Place Bound Bottom")
		(35 "F.Fab" user "Ref Des/Assembly Top")
		(33 "B.Fab" user "Ref Des/Assembly Bottom")
	)
	(footprint ""
		(layer "F.Cu")
		(at 70.409054 -335.000092)
		(property "Reference" "PU37"
			(at 2.996946 -8.508238 0)
			(unlocked yes)
			(layer "F.SilkS")
			(effects
				(font
					(size 0.7874 0.5842)
					(thickness 0.1524)
				)
				(justify left)
			)
		)
		(property "Value" ""
			(at 0 0 0)
			(layer "F.Fab")
			(effects
				(font
					(size 1.27 1.27)
				)
			)
		)
		(duplicate_pad_numbers_are_jumpers no)
		(fp_line
			(start -2.500122 -2.999994)
			(end -2.24409 -2.999994)
			(stroke
				(width 0.1524)
				(type default)
			)
			(layer "F.SilkS")
		)
		(fp_line
			(start -2.500122 -2.529078)
			(end -2.500122 -2.999994)
			(stroke
				(width 0.1524)
				(type default)
			)
			(layer "F.SilkS")
		)
		(fp_line
			(start -2.500122 0.6604)
			(end -2.500122 0.229108)
			(stroke
				(width 0.1524)
				(type default)
			)
			(layer "F.SilkS")
		)
		(fp_line
			(start -2.500122 2.999994)
			(end -2.500122 2.339594)
			(stroke
				(width 0.1524)
				(type default)
			)
			(layer "F.SilkS")
		)
		(fp_line
			(start -2.2987 2.999994)
			(end -2.500122 2.999994)
			(stroke
				(width 0.1524)
				(type default)
			)
			(layer "F.SilkS")
		)
		(fp_line
			(start 2.31394 -2.999994)
			(end 2.500122 -2.999994)
			(stroke
				(width 0.1524)
				(type default)
			)
			(layer "F.SilkS")
		)
		(fp_line
			(start 2.500122 -2.999994)
			(end 2.500122 -2.44348)
			(stroke
				(width 0.1524)
				(type default)
			)
			(layer "F.SilkS")
		)
		(fp_line
			(start 2.500122 2.339594)
			(end 2.500122 2.999994)
			(stroke
				(width 0.1524)
				(type default)
			)
			(layer "F.SilkS")
		)
		(fp_line
			(start 2.500122 2.999994)
			(end 2.2987 2.999994)
			(stroke
				(width 0.1524)
				(type default)
			)
			(layer "F.SilkS")
		)
		(fp_poly
			(pts
				(xy -2.749296 -2.412238) (xy -3.422904 -2.636774) (xy -2.973832 -3.085846)
			)
			(stroke
				(width 0)
				(type default)
			)
			(fill yes)
			(layer "F.SilkS")
		)
		(fp_line
			(start -2.500122 -2.999994)
			(end 2.500122 -2.999994)
			(stroke
				(width 0.1)
				(type default)
			)
			(layer "F.Fab")
		)
		(fp_line
			(start -2.500122 2.999994)
			(end -2.500122 -2.999994)
			(stroke
				(width 0.1)
				(type default)
			)
			(layer "F.Fab")
		)
		(fp_line
			(start 2.500122 -2.999994)
			(end 2.500122 2.999994)
			(stroke
				(width 0.1)
				(type default)
			)
			(layer "F.Fab")
		)
		(fp_line
			(start 2.500122 2.999994)
			(end -2.500122 2.999994)
			(stroke
				(width 0.1)
				(type default)
			)
			(layer "F.Fab")
		)
		(fp_poly
			(pts
				(xy -4.218432 -2.783078) (xy -4.218432 -1.767078) (xy -3.202432 -2.275078)
			)
			(stroke
				(width 0)
				(type default)
			)
			(fill yes)
			(layer "F.Fab")
		)
		(pad "1" smd rect
			(at -2.400046 -2.275078 90)
			(size 0.2286 0.6096)
			(layers "F.Cu" "F.Mask" "F.Paste")
			(net "PVDDCR_CPU1_P1_VOS3")
		)
		(pad "2" smd rect
			(at -2.400046 -1.82499 90)
			(size 0.2286 0.6096)
			(layers "F.Cu" "F.Mask" "F.Paste")
			(net "GND")
		)
		(pad "3" smd rect
			(at -2.400046 -1.374902 90)
			(size 0.2286 0.6096)
			(layers "F.Cu" "F.Mask" "F.Paste")
			(net "PVDDCR_CPU1_P1_VCC3")
		)
		(pad "4" smd rect
			(at -2.400046 -0.925068 90)
			(size 0.2286 0.6096)
			(layers "F.Cu" "F.Mask" "F.Paste")
			(net "PVDDCR_CPU1_P1_PVCC")
		)
		(pad "5" smd rect
			(at -2.400046 -0.47498 90)
			(size 0.2286 0.6096)
			(layers "F.Cu" "F.Mask" "F.Paste")
			(net "GND")
		)
		(pad "6" smd rect
			(at -2.400046 -0.024892 90)
			(size 0.2286 0.6096)
			(layers "F.Cu" "F.Mask" "F.Paste")
			(net "NC_PVDDCR_CPU1_P1_GL1_3")
		)
		(pad "7_9-20_24" smd circle
			(at 0 1.150112 90)
			(size 0 0)
			(layers "F.Cu" "F.Mask" "F.Paste")
			(net "GND")
		)
		(pad "10_19" smd rect
			(at 0 2.899918 90)
			(size 0.6096 4.318)
			(layers "F.Cu" "F.Mask" "F.Paste")
			(net "SW_PVDDCR_CPU1_P1_SW3")
		)
		(pad "25_29" smd rect
			(at 1.549908 -1.279906 270)
			(size 2.0574 2.3114)
			(layers "F.Cu" "F.Mask" "F.Paste")
			(net "SW_P12V_AUX_PVDDCR_CPU1_P1_FLT")
		)
		(pad "30" smd rect
			(at 2.05994 -2.899918)
			(size 0.2286 0.6096)
			(layers "F.Cu" "F.Mask" "F.Paste")
			(net "SW_P12V_AUX_PVDDCR_CPU1_P1_FLT")
		)
		(pad "31" smd rect
			(at 1.610106 -2.899918)
			(size 0.2286 0.6096)
			(layers "F.Cu" "F.Mask" "F.Paste")
			(net "NC_PVDDCR_CPU1_P1_DNC3")
		)
		(pad "32" smd rect
			(at 1.160018 -2.899918)
			(size 0.2286 0.6096)
			(layers "F.Cu" "F.Mask" "F.Paste")
			(net "SW_PVDDCR_CPU1_P1_BOOTR3")
		)
		(pad "33" smd rect
			(at 0.70993 -2.899918)
			(size 0.2286 0.6096)
			(layers "F.Cu" "F.Mask" "F.Paste")
			(net "SW_PVDDCR_CPU1_P1_BOOT3")
		)
		(pad "34" smd rect
			(at 0.260096 -2.899918)
			(size 0.2286 0.6096)
			(layers "F.Cu" "F.Mask" "F.Paste")
			(net "PVDDCR_CPU1_P1_PWM3")
		)
		(pad "35" smd rect
			(at -0.189992 -2.899918)
			(size 0.2286 0.6096)
			(layers "F.Cu" "F.Mask" "F.Paste")
			(net "PVDDCR_CPU1_P1_VCC3")
		)
		(pad "36" smd rect
			(at -0.64008 -2.899918)
			(size 0.2286 0.6096)
			(layers "F.Cu" "F.Mask" "F.Paste")
			(net "PVDDCR_CPU1_P1_TEMP0")
		)
		(pad "37" smd rect
			(at -1.089914 -2.899918)
			(size 0.2286 0.6096)
			(layers "F.Cu" "F.Mask" "F.Paste")
			(net "PVDDCR_CPU1_P1_LSET3")
		)
		(pad "38" smd rect
			(at -1.540002 -2.899918)
			(size 0.2286 0.6096)
			(layers "F.Cu" "F.Mask" "F.Paste")
			(net "PVDDCR_CPU1_P1_IMON3")
		)
		(pad "39" smd rect
			(at -1.99009 -2.899918)
			(size 0.2286 0.6096)
			(layers "F.Cu" "F.Mask" "F.Paste")
			(net "PVDDCR_CPU1_P1_VCCS")
		)
		(pad "40" smd rect
			(at -0.87503 -1.27508)
			(size 1.7526 1.9558)
			(layers "F.Cu" "F.Mask" "F.Paste")
			(net "GND")
		)
		(pad "41" smd rect
			(at -1.525016 0.249936 270)
			(size 0.3048 0.4572)
			(layers "F.Cu" "F.Mask" "F.Paste")
			(net "NC_PVDDCR_CPU1_P1_GL2_3")
		)
		(zone
			(layer "F.Cu")
			(hatch none 0.5)
			(connect_pads
				(clearance 0)
			)
			(min_thickness 0.25)
			(keepout
				(tracks not_allowed)
				(vias allowed)
				(pads allowed)
				(copperpour not_allowed)
				(footprints allowed)
			)
			(placement
				(enabled no)
				(sheetname "")
			)
			(fill
				(thermal_gap 0.5)
				(thermal_bridge_width 0.5)
				(island_removal_mode 0)
			)
			(polygon
				(pts
					(xy 67.908932 -332.417674) (xy 67.908932 -332.749398) (xy 72.909176 -332.749398) (xy 72.909176 -332.411578)
					(xy 72.618854 -332.411578) (xy 72.618854 -332.455774) (xy 68.199254 -332.455774) (xy 68.199254 -332.417674)
				)
			)
		)
		(zone
			(layer "F.Cu")
			(hatch none 0.5)
			(connect_pads
				(clearance 0)
			)
			(min_thickness 0.25)
			(keepout
				(tracks not_allowed)
				(vias allowed)
				(pads allowed)
				(copperpour not_allowed)
				(footprints allowed)
			)
			(placement
				(enabled no)
				(sheetname "")
			)
			(fill
				(thermal_gap 0.5)
				(thermal_bridge_width 0.5)
				(island_removal_mode 0)
			)
			(polygon
				(pts
					(xy 70.461124 -335.246472) (xy 70.461124 -337.303872) (xy 68.606924 -337.303872) (xy 68.606924 -337.062826)
					(xy 68.364608 -337.062826) (xy 68.364608 -337.54441) (xy 72.286368 -337.54441) (xy 72.286368 -337.359498)
					(xy 70.752462 -337.359498) (xy 70.752462 -335.200498) (xy 72.909176 -335.200498) (xy 72.909176 -334.950816)
					(xy 70.75678 -334.950816)
				)
			)
		)
	)
)
